# BASEBOARD_FAB2 (Tioga Pass) — schematic netlist excerpt (pin names and nets, part order shuffled) for the footprints in the layout excerpt that follows; sources: Cadence DE-HDL packaged netlist, KiCad conversion of Wiwynn_Tioga_Pass_MB.brd

C1D26  CAP_A  0.1UF 16V 10% X7R  pkg 0402V  page 199 : A = A_HSC_UV ; B = AGND_HSC
R1L2  RES  10.0 1% CHIP  pkg 0402  page 155 : A = FM_CPLD_DBG_PWR_EN_N ; B = FM_CPLD_DBG_PWR_EN_R_N

(kicad_pcb
	(version 20260206)
	(generator "pcbnew")
	(generator_version "10.0")
	(general
		(thickness 1.6)
		(legacy_teardrops no)
	)
	(paper "A4")
	(title_block
		(title "Wiwynn_Tioga_Pass_MB.brd")
		(comment 1 "Tioga Pass / footprints 318-319 of 4770")
	)
	(layers
		(0 "F.Cu" signal "TOP")
		(4 "In1.Cu" signal "L2GND")
		(6 "In2.Cu" signal "L3")
		(8 "In3.Cu" signal "L4GND")
		(10 "In4.Cu" signal "L5")
		(12 "In5.Cu" signal "L6GND")
		(14 "In6.Cu" signal "L7VCC")
		(16 "In7.Cu" signal "L8VCC")
		(18 "In8.Cu" signal "L9GND")
		(20 "In9.Cu" signal "L10")
		(22 "In10.Cu" signal "L11GND")
		(24 "In11.Cu" signal "L12")
		(26 "In12.Cu" signal "L13GND")
		(2 "B.Cu" signal "BOTTOM")
		(9 "F.Adhes" user "F.Adhesive")
		(11 "B.Adhes" user "B.Adhesive")
		(13 "F.Paste" user "Package Geometry/Pastemask Top")
		(15 "B.Paste" user "Package Geometry/Pastemask Bottom")
		(5 "F.SilkS" user "Ref Des/Silkscreen Top")
		(7 "B.SilkS" user "Ref Des/Silkscreen Bottom")
		(1 "F.Mask" user "Board Geometry/Soldermask Top")
		(3 "B.Mask" user "Board Geometry/Soldermask Bottom")
		(17 "Dwgs.User" user "User.Drawings")
		(19 "Cmts.User" user "User.Comments")
		(21 "Eco1.User" user "User.Eco1")
		(23 "Eco2.User" user "User.Eco2")
		(25 "Edge.Cuts" user "Board Geometry/Outline")
		(27 "Margin" user)
		(31 "F.CrtYd" user "Package Geometry/Place Bound Top")
		(29 "B.CrtYd" user "Package Geometry/Place Bound Bottom")
		(35 "F.Fab" user "Ref Des/Assembly Top")
		(33 "B.Fab" user "Ref Des/Assembly Bottom")
	)
	(footprint ""
		(layer "F.Cu")
		(at 19.558 -70.866)
		(property "Reference" "C1D26"
			(at 0 0 0)
			(layer "F.SilkS")
			(hide yes)
			(effects
				(font
					(size 1.27 1.27)
				)
			)
		)
		(property "Value" ""
			(at 0 0 0)
			(layer "F.Fab")
			(effects
				(font
					(size 1.27 1.27)
				)
			)
		)
		(duplicate_pad_numbers_are_jumpers no)
		(fp_poly
			(pts
				(xy 0.3048 -0.1016) (xy 0.3048 0.9906) (xy -0.3048 0.9906) (xy -0.3048 -0.1016)
			)
			(stroke
				(width 0)
				(type default)
			)
			(fill no)
			(layer "F.CrtYd")
		)
		(fp_line
			(start -0.3048 -0.1016)
			(end -0.3048 0.9906)
			(stroke
				(width 0.1)
				(type default)
			)
			(layer "F.Fab")
		)
		(fp_line
			(start -0.3048 0.9906)
			(end 0.3048 0.9906)
			(stroke
				(width 0.1)
				(type default)
			)
			(layer "F.Fab")
		)
		(fp_line
			(start 0.3048 -0.1016)
			(end -0.3048 -0.1016)
			(stroke
				(width 0.1)
				(type default)
			)
			(layer "F.Fab")
		)
		(fp_line
			(start 0.3048 0.9906)
			(end 0.3048 -0.1016)
			(stroke
				(width 0.1)
				(type default)
			)
			(layer "F.Fab")
		)
		(pad "1" smd rect
			(at 0 0)
			(size 0.508 0.508)
			(layers "F.Cu" "F.Mask" "F.Paste")
			(net "A_HSC_UV")
		)
		(pad "2" smd rect
			(at 0 0.889)
			(size 0.508 0.508)
			(layers "F.Cu" "F.Mask" "F.Paste")
			(net "AGND_HSC")
		)
		(zone
			(layer "F.Cu")
			(hatch none 0.5)
			(connect_pads
				(clearance 0)
			)
			(min_thickness 0.25)
			(keepout
				(tracks allowed)
				(vias not_allowed)
				(pads allowed)
				(copperpour not_allowed)
				(footprints allowed)
			)
			(placement
				(enabled no)
				(sheetname "")
			)
			(fill
				(thermal_gap 0.5)
				(thermal_bridge_width 0.5)
				(island_removal_mode 0)
			)
			(polygon
				(pts
					(xy 19.304 -70.612) (xy 19.812 -70.612) (xy 19.812 -70.231) (xy 19.304 -70.231)
				)
			)
		)
		(zone
			(layer "F.Cu")
			(hatch none 0.5)
			(connect_pads
				(clearance 0)
			)
			(min_thickness 0.25)
			(keepout
				(tracks not_allowed)
				(vias allowed)
				(pads allowed)
				(copperpour not_allowed)
				(footprints allowed)
			)
			(placement
				(enabled no)
				(sheetname "")
			)
			(fill
				(thermal_gap 0.5)
				(thermal_bridge_width 0.5)
				(island_removal_mode 0)
			)
			(polygon
				(pts
					(xy 19.304 -70.231) (xy 19.812 -70.231) (xy 19.812 -70.612) (xy 19.304 -70.612)
				)
			)
		)
	)
	(footprint ""
		(layer "F.Cu")
		(at 477.978724 -150.256494)
		(property "Reference" "R1L2"
			(at 0 0 0)
			(layer "F.SilkS")
			(hide yes)
			(effects
				(font
					(size 1.27 1.27)
				)
			)
		)
		(property "Value" ""
			(at 0 0 0)
			(layer "F.Fab")
			(effects
				(font
					(size 1.27 1.27)
				)
			)
		)
		(duplicate_pad_numbers_are_jumpers no)
		(fp_poly
			(pts
				(xy -0.2794 -0.1016) (xy 0.2794 -0.1016) (xy 0.2794 0.9906) (xy -0.2794 0.9906)
			)
			(stroke
				(width 0)
				(type default)
			)
			(fill no)
			(layer "F.CrtYd")
		)
		(fp_line
			(start -0.2794 -0.1016)
			(end -0.2794 0.9906)
			(stroke
				(width 0.1)
				(type default)
			)
			(layer "F.Fab")
		)
		(fp_line
			(start -0.2794 0.9906)
			(end 0.2794 0.9906)
			(stroke
				(width 0.1)
				(type default)
			)
			(layer "F.Fab")
		)
		(fp_line
			(start 0.2794 -0.1016)
			(end -0.2794 -0.1016)
			(stroke
				(width 0.1)
				(type default)
			)
			(layer "F.Fab")
		)
		(fp_line
			(start 0.2794 0.9906)
			(end 0.2794 -0.1016)
			(stroke
				(width 0.1)
				(type default)
			)
			(layer "F.Fab")
		)
		(pad "1" smd rect
			(at 0 0)
			(size 0.508 0.508)
			(layers "F.Cu" "F.Mask" "F.Paste")
			(net "FM_CPLD_DBG_PWR_EN_N")
		)
		(pad "2" smd rect
			(at 0 0.889)
			(size 0.508 0.508)
			(layers "F.Cu" "F.Mask" "F.Paste")
			(net "FM_CPLD_DBG_PWR_EN_R_N")
		)
		(zone
			(layer "F.Cu")
			(hatch none 0.5)
			(connect_pads
				(clearance 0)
			)
			(min_thickness 0.25)
			(keepout
				(tracks allowed)
				(vias not_allowed)
				(pads allowed)
				(copperpour not_allowed)
				(footprints allowed)
			)
			(placement
				(enabled no)
				(sheetname "")
			)
			(fill
				(thermal_gap 0.5)
				(thermal_bridge_width 0.5)
				(island_removal_mode 0)
			)
			(polygon
				(pts
					(xy 477.724724 -150.002494) (xy 478.232724 -150.002494) (xy 478.232724 -149.621494) (xy 477.724724 -149.621494)
				)
			)
		)
		(zone
			(layer "F.Cu")
			(hatch none 0.5)
			(connect_pads
				(clearance 0)
			)
			(min_thickness 0.25)
			(keepout
				(tracks not_allowed)
				(vias allowed)
				(pads allowed)
				(copperpour not_allowed)
				(footprints allowed)
			)
			(placement
				(enabled no)
				(sheetname "")
			)
			(fill
				(thermal_gap 0.5)
				(thermal_bridge_width 0.5)
				(island_removal_mode 0)
			)
			(polygon
				(pts
					(xy 477.724724 -149.621494) (xy 478.232724 -149.621494) (xy 478.232724 -150.002494) (xy 477.724724 -150.002494)
				)
			)
		)
	)
)
